(kicad_pcb
	(version 20241229)
	(generator "pcbnew")
	(generator_version "9.0")
	(general
		(thickness 1.61)
		(legacy_teardrops no)
	)
	(paper "A3")
	(title_block
		(title "SO-DIMM DDR5 Tester")
		(date "2025-11-26")
		(rev "1.3.0")
		(comment 9 "footprints 401-406 of 627")
	)
	(layers
		(0 "F.Cu" signal)
		(4 "In1.Cu" power)
		(6 "In2.Cu" mixed)
		(8 "In3.Cu" power)
		(10 "In4.Cu" mixed)
		(12 "In5.Cu" power)
		(14 "In6.Cu" mixed)
		(16 "In7.Cu" power)
		(18 "In8.Cu" power)
		(20 "In9.Cu" mixed)
		(22 "In10.Cu" power)
		(2 "B.Cu" signal)
		(9 "F.Adhes" user "F.Adhesive")
		(11 "B.Adhes" user "B.Adhesive")
		(13 "F.Paste" user)
		(15 "B.Paste" user)
		(5 "F.SilkS" user "F.Silkscreen")
		(7 "B.SilkS" user "B.Silkscreen")
		(1 "F.Mask" user)
		(3 "B.Mask" user)
		(17 "Dwgs.User" user "User.Drawings")
		(19 "Cmts.User" user "User.Comments")
		(21 "Eco1.User" user "User.Eco1")
		(23 "Eco2.User" user "User.Eco2")
		(25 "Edge.Cuts" user)
		(27 "Margin" user)
		(31 "F.CrtYd" user "F.Courtyard")
		(29 "B.CrtYd" user "B.Courtyard")
		(35 "F.Fab" user)
		(33 "B.Fab" user)
	)
	(footprint "antmicro-footprints:TP_SMD_1mm"
		(layer "B.Cu")
		(at 186.4 182.1 180)
		(property "Reference" "TP34"
			(at 0 0.731898 0)
			(layer "B.SilkS")
			(hide yes)
			(effects
				(font
					(size 0.7 0.7)
					(thickness 0.15)
				)
				(justify left bottom mirror)
			)
		)
		(property "Value" "TP_1mm_SMD"
			(at 0 -1.4 0)
			(layer "B.Fab")
			(effects
				(font
					(size 0.7 0.7)
					(thickness 0.15)
				)
				(justify left bottom mirror)
			)
		)
		(property "MPN" ""
			(at 0 0 0)
			(unlocked yes)
			(layer "B.Fab")
			(hide yes)
			(effects
				(font
					(size 1 1)
					(thickness 0.15)
				)
				(justify mirror)
			)
		)
		(property "Manufacturer" ""
			(at 0 0 0)
			(unlocked yes)
			(layer "B.Fab")
			(hide yes)
			(effects
				(font
					(size 1 1)
					(thickness 0.15)
				)
				(justify mirror)
			)
		)
		(property "Author" "Antmicro"
			(at 0 0 0)
			(unlocked yes)
			(layer "B.Fab")
			(hide yes)
			(effects
				(font
					(size 1 1)
					(thickness 0.15)
				)
				(justify mirror)
			)
		)
		(property "License" "Apache-2.0"
			(at 0 0 0)
			(unlocked yes)
			(layer "B.Fab")
			(hide yes)
			(effects
				(font
					(size 1 1)
					(thickness 0.15)
				)
				(justify mirror)
			)
		)
		(sheetname "/Supply/")
		(sheetfile "supply.kicad_sch")
		(attr exclude_from_pos_files)
		(fp_circle
			(center 0 0)
			(end 0.6 0)
			(stroke
				(width 0.05)
				(type default)
			)
			(fill no)
			(layer "B.CrtYd")
		)
		(fp_text user "Author: Antmicro"
			(at -0.5 -4 0)
			(layer "B.Fab")
			(effects
				(font
					(size 0.7 0.7)
					(thickness 0.15)
				)
				(justify left bottom mirror)
			)
		)
		(fp_text user "${REFERENCE}"
			(at -0.5 -2.8 0)
			(layer "B.Fab")
			(effects
				(font
					(size 0.7 0.7)
					(thickness 0.15)
				)
				(justify left bottom mirror)
			)
		)
		(fp_text user "License: Apache-2.0"
			(at -0.5 -5.2 0)
			(layer "B.Fab")
			(effects
				(font
					(size 0.7 0.7)
					(thickness 0.15)
				)
				(justify left bottom mirror)
			)
		)
		(pad "1" smd circle
			(at 0 0 180)
			(size 1 1)
			(layers "B.Cu" "B.Mask")
			(net 188 "+1V8")
			(pinfunction "1")
			(pintype "passive")
		)
	)
	(footprint "antmicro-footprints:C_0402_1005Metric"
		(layer "B.Cu")
		(at 119.580501 175.926 90)
		(descr "Capacitor SMD 0402")
		(tags "capacitor SMD 0402")
		(property "Reference" "C4"
			(at 0 0.699 270)
			(layer "B.SilkS")
			(hide yes)
			(effects
				(font
					(size 0.7 0.7)
					(thickness 0.15)
				)
				(justify left bottom mirror)
			)
		)
		(property "Value" "C_100n_0402"
			(at -1.022927 -2.155213 270)
			(layer "B.Fab")
			(effects
				(font
					(size 0.7 0.7)
					(thickness 0.15)
				)
				(justify left bottom mirror)
			)
		)
		(property "Datasheet" "https://www.murata.com/products/productdetail?partno=GRM155R61H104KE14%23"
			(at 0 0 90)
			(layer "F.Fab")
			(hide yes)
			(effects
				(font
					(size 1.27 1.27)
					(thickness 0.15)
				)
			)
		)
		(property "Author" "Antmicro"
			(at 295.506501 56.345499 0)
			(layer "B.Fab")
			(hide yes)
			(effects
				(font
					(size 1 1)
					(thickness 0.15)
				)
				(justify mirror)
			)
		)
		(property "Dielectric" "X5R"
			(at 295.506501 56.345499 0)
			(layer "B.Fab")
			(hide yes)
			(effects
				(font
					(size 1 1)
					(thickness 0.15)
				)
				(justify mirror)
			)
		)
		(property "License" "Apache-2.0"
			(at 295.506501 56.345499 0)
			(layer "B.Fab")
			(hide yes)
			(effects
				(font
					(size 1 1)
					(thickness 0.15)
				)
				(justify mirror)
			)
		)
		(property "MPN" "GRM155R61H104KE14D"
			(at 295.506501 56.345499 0)
			(layer "B.Fab")
			(hide yes)
			(effects
				(font
					(size 1 1)
					(thickness 0.15)
				)
				(justify mirror)
			)
		)
		(property "Manufacturer" "Murata"
			(at 295.506501 56.345499 0)
			(layer "B.Fab")
			(hide yes)
			(effects
				(font
					(size 1 1)
					(thickness 0.15)
				)
				(justify mirror)
			)
		)
		(property "Val" "100n"
			(at 295.506501 56.345499 0)
			(layer "B.Fab")
			(hide yes)
			(effects
				(font
					(size 1 1)
					(thickness 0.15)
				)
				(justify mirror)
			)
		)
		(property "Voltage" "50V"
			(at 295.506501 56.345499 0)
			(layer "B.Fab")
			(hide yes)
			(effects
				(font
					(size 1 1)
					(thickness 0.15)
				)
				(justify mirror)
			)
		)
		(sheetname "/HyperRAM + QSPI Flash/")
		(sheetfile "hyperram-flash.kicad_sch")
		(attr smd)
		(fp_rect
			(start -0.9659 0.481258)
			(end 0.9649 -0.458742)
			(stroke
				(width 0.05)
				(type solid)
			)
			(fill no)
			(layer "B.CrtYd")
		)
		(fp_line
			(start 0.499 -0.248)
			(end -0.499 -0.248)
			(stroke
				(width 0.15)
				(type solid)
			)
			(layer "B.Fab")
		)
		(fp_line
			(start -0.499 -0.248)
			(end -0.499 0.25)
			(stroke
				(width 0.15)
				(type solid)
			)
			(layer "B.Fab")
		)
		(fp_line
			(start 0.499 0.25)
			(end 0.499 -0.248)
			(stroke
				(width 0.15)
				(type solid)
			)
			(layer "B.Fab")
		)
		(fp_line
			(start -0.499 0.25)
			(end 0.499 0.25)
			(stroke
				(width 0.15)
				(type solid)
			)
			(layer "B.Fab")
		)
		(pad "1" smd roundrect
			(at -0.484 0 90)
			(size 0.59 0.64)
			(layers "B.Cu" "B.Mask" "B.Paste")
			(roundrect_rratio 0.25)
			(net 200 "+3V3")
			(pintype "passive")
		)
		(pad "2" smd roundrect
			(at 0.484 0 90)
			(size 0.59 0.64)
			(layers "B.Cu" "B.Mask" "B.Paste")
			(roundrect_rratio 0.25)
			(net 1 "GND")
			(pintype "passive")
		)
	)
	(footprint "antmicro-footprints:R_0402_1005Metric_EIA"
		(layer "B.Cu")
		(at 141.875001 170.3025)
		(descr "Resistor SMD 0402 (1005 Metric), square (rectangular) end terminal, IPC_7351 nominal, (Body size source: IPC-SM-782 page 76, https://www.pcb-3d.com/wordpress/wp-content/uploads/ipc-sm-782a_amendment_1_and_2.pdf)")
		(tags "resistor 0402")
		(property "Reference" "R134"
			(at 0 1.17 180)
			(layer "B.SilkS")
			(hide yes)
			(effects
				(font
					(size 0.7 0.7)
					(thickness 0.15)
				)
				(justify left bottom mirror)
			)
		)
		(property "Value" "R_80R6_0402_EIA"
			(at 0 -1.169 180)
			(layer "B.Fab")
			(effects
				(font
					(size 0.7 0.7)
					(thickness 0.15)
				)
				(justify left bottom mirror)
			)
		)
		(property "Datasheet" "https://www.bourns.com/docs/product-datasheets/cr.pdf"
			(at 0 0 0)
			(layer "F.Fab")
			(hide yes)
			(effects
				(font
					(size 1.27 1.27)
					(thickness 0.15)
				)
			)
		)
		(property "Author" "Antmicro"
			(at 0 0 0)
			(layer "B.Fab")
			(hide yes)
			(effects
				(font
					(size 1 1)
					(thickness 0.15)
				)
				(justify mirror)
			)
		)
		(property "License" "Apache-2.0"
			(at 0 0 0)
			(layer "B.Fab")
			(hide yes)
			(effects
				(font
					(size 1 1)
					(thickness 0.15)
				)
				(justify mirror)
			)
		)
		(property "MPN" "MC00625W0402180R6"
			(at 0 0 0)
			(layer "B.Fab")
			(hide yes)
			(effects
				(font
					(size 1 1)
					(thickness 0.15)
				)
				(justify mirror)
			)
		)
		(property "Manufacturer" "Multicomp Pro"
			(at 0 0 0)
			(layer "B.Fab")
			(hide yes)
			(effects
				(font
					(size 1 1)
					(thickness 0.15)
				)
				(justify mirror)
			)
		)
		(property "Tolerance" "1%"
			(at 0 0 0)
			(layer "B.Fab")
			(hide yes)
			(effects
				(font
					(size 1 1)
					(thickness 0.15)
				)
				(justify mirror)
			)
		)
		(property "Val" "80R6"
			(at 0 0 0)
			(layer "B.Fab")
			(hide yes)
			(effects
				(font
					(size 1 1)
					(thickness 0.15)
				)
				(justify mirror)
			)
		)
		(sheetname "/FPGA banks HP/")
		(sheetfile "fpga-banks-32-34.kicad_sch")
		(attr smd)
		(fp_line
			(start -0.95 -0.45)
			(end -0.95 0.46)
			(stroke
				(width 0.05)
				(type solid)
			)
			(layer "B.CrtYd")
		)
		(fp_line
			(start -0.95 0.46)
			(end 0.9652 0.46)
			(stroke
				(width 0.05)
				(type solid)
			)
			(layer "B.CrtYd")
		)
		(fp_line
			(start 0.9652 -0.45)
			(end -0.95 -0.45)
			(stroke
				(width 0.05)
				(type solid)
			)
			(layer "B.CrtYd")
		)
		(fp_line
			(start 0.9652 0.46)
			(end 0.9652 -0.45)
			(stroke
				(width 0.05)
				(type solid)
			)
			(layer "B.CrtYd")
		)
		(fp_line
			(start -0.5 -0.249)
			(end -0.5 0.25)
			(stroke
				(width 0.15)
				(type solid)
			)
			(layer "B.Fab")
		)
		(fp_line
			(start -0.5 0.25)
			(end 0.499 0.25)
			(stroke
				(width 0.15)
				(type solid)
			)
			(layer "B.Fab")
		)
		(fp_line
			(start 0.499 -0.249)
			(end -0.5 -0.249)
			(stroke
				(width 0.15)
				(type solid)
			)
			(layer "B.Fab")
		)
		(fp_line
			(start 0.499 0.25)
			(end 0.499 -0.249)
			(stroke
				(width 0.15)
				(type solid)
			)
			(layer "B.Fab")
		)
		(pad "1" smd roundrect
			(at -0.5 0 270)
			(size 0.6 0.6)
			(layers "B.Cu" "B.Mask" "B.Paste")
			(roundrect_rratio 0.25)
			(net 685 "/FPGA banks HP/VRP")
			(pintype "passive")
		)
		(pad "2" smd roundrect
			(at 0.499 0)
			(size 0.6 0.6)
			(layers "B.Cu" "B.Mask" "B.Paste")
			(roundrect_rratio 0.25)
			(net 1 "GND")
			(pintype "passive")
		)
	)
	(footprint "antmicro-footprints:R_0402_1005Metric"
		(layer "B.Cu")
		(at 184.25 191.48 90)
		(descr "Resistor SMD 0402")
		(tags "resistor SMD 0402")
		(property "Reference" "R37"
			(at -1.42 0.6 90)
			(layer "B.SilkS")
			(effects
				(font
					(size 0.7 0.7)
					(thickness 0.15)
				)
				(justify right top mirror)
			)
		)
		(property "Value" "R_0R_0402"
			(at -1.011843 -1.772046 90)
			(layer "B.Fab")
			(effects
				(font
					(size 0.7 0.7)
					(thickness 0.15)
				)
				(justify right top mirror)
			)
		)
		(property "Datasheet" "https://industrial.panasonic.com/cdbs/www-data/pdf/RDA0000/AOA0000C301.pdf"
			(at 0 0 90)
			(layer "B.Fab")
			(hide yes)
			(effects
				(font
					(size 1.27 1.27)
					(thickness 0.15)
				)
				(justify mirror)
			)
		)
		(property "Manufacturer" "Panasonic"
			(at 0 0 270)
			(unlocked yes)
			(layer "B.Fab")
			(hide yes)
			(effects
				(font
					(size 1 1)
					(thickness 0.15)
				)
				(justify mirror)
			)
		)
		(property "MPN" "ERJ2GE0R00X"
			(at 0 0 270)
			(unlocked yes)
			(layer "B.Fab")
			(hide yes)
			(effects
				(font
					(size 1 1)
					(thickness 0.15)
				)
				(justify mirror)
			)
		)
		(property "Val" "0R"
			(at 0 0 270)
			(unlocked yes)
			(layer "B.Fab")
			(hide yes)
			(effects
				(font
					(size 1 1)
					(thickness 0.15)
				)
				(justify mirror)
			)
		)
		(property "License" "Apache-2.0"
			(at 0 0 270)
			(unlocked yes)
			(layer "B.Fab")
			(hide yes)
			(effects
				(font
					(size 1 1)
					(thickness 0.15)
				)
				(justify mirror)
			)
		)
		(property "Author" "Antmicro"
			(at 0 0 270)
			(unlocked yes)
			(layer "B.Fab")
			(hide yes)
			(effects
				(font
					(size 1 1)
					(thickness 0.15)
				)
				(justify mirror)
			)
		)
		(property "Tolerance" ""
			(at 0 0 270)
			(unlocked yes)
			(layer "B.Fab")
			(hide yes)
			(effects
				(font
					(size 1 1)
					(thickness 0.15)
				)
				(justify mirror)
			)
		)
		(property "Current" "1A"
			(at 0 0 270)
			(unlocked yes)
			(layer "B.Fab")
			(hide yes)
			(effects
				(font
					(size 1 1)
					(thickness 0.15)
				)
				(justify mirror)
			)
		)
		(sheetname "/I^{2}C/")
		(sheetfile "i2c.kicad_sch")
		(attr smd)
		(fp_poly
			(pts
				(xy -0.925 0.47) (xy -0.925 -0.47) (xy 0.925 -0.47) (xy 0.925 0.47)
			)
			(stroke
				(width 0.05)
				(type default)
			)
			(fill no)
			(layer "B.CrtYd")
		)
		(fp_poly
			(pts
				(xy -0.5 0.25) (xy -0.5 -0.25) (xy 0.5 -0.25) (xy 0.5 0.25)
			)
			(stroke
				(width 0.15)
				(type solid)
			)
			(fill no)
			(layer "B.Fab")
		)
		(fp_text user "Author: Antmicro"
			(at -0.95 -4.169 90)
			(layer "B.Fab")
			(effects
				(font
					(size 0.7 0.7)
					(thickness 0.15)
				)
				(justify right top mirror)
			)
		)
		(fp_text user "${REFERENCE}"
			(at -0.95 -3.168 90)
			(layer "B.Fab")
			(effects
				(font
					(size 0.7 0.7)
					(thickness 0.15)
				)
				(justify right top mirror)
			)
		)
		(fp_text user "License: Apache-2.0"
			(at -0.949999 -5.169 90)
			(layer "B.Fab")
			(effects
				(font
					(size 0.7 0.7)
					(thickness 0.15)
				)
				(justify right top mirror)
			)
		)
		(pad "1" smd roundrect
			(at -0.48 0 90)
			(size 0.59 0.64)
			(layers "B.Cu" "B.Mask" "B.Paste")
			(roundrect_rratio 0.25)
			(net 691 "/I^{2}C/PWR.SCL")
			(pintype "passive")
		)
		(pad "2" smd roundrect
			(at 0.48 0 90)
			(size 0.59 0.64)
			(layers "B.Cu" "B.Mask" "B.Paste")
			(roundrect_rratio 0.25)
			(net 762 "Net-(U34-SCL)")
			(pintype "passive")
		)
	)
	(footprint "antmicro-footprints:C_0402_1005Metric"
		(layer "B.Cu")
		(at 198.1 138.765 90)
		(descr "Capacitor SMD 0402")
		(tags "capacitor SMD 0402")
		(property "Reference" "C195"
			(at 0 0.699 270)
			(layer "B.SilkS")
			(hide yes)
			(effects
				(font
					(size 0.7 0.7)
					(thickness 0.15)
				)
				(justify left bottom mirror)
			)
		)
		(property "Value" "C_100n_0402"
			(at -1.022927 -2.155213 270)
			(layer "B.Fab")
			(effects
				(font
					(size 0.7 0.7)
					(thickness 0.15)
				)
				(justify left bottom mirror)
			)
		)
		(property "Datasheet" "https://www.murata.com/products/productdetail?partno=GRM155R61H104KE14%23"
			(at 0 0 90)
			(layer "F.Fab")
			(hide yes)
			(effects
				(font
					(size 1.27 1.27)
					(thickness 0.15)
				)
			)
		)
		(property "Author" "Antmicro"
			(at 336.865 -59.335 0)
			(layer "B.Fab")
			(hide yes)
			(effects
				(font
					(size 1 1)
					(thickness 0.15)
				)
				(justify mirror)
			)
		)
		(property "Dielectric" "X5R"
			(at 336.865 -59.335 0)
			(layer "B.Fab")
			(hide yes)
			(effects
				(font
					(size 1 1)
					(thickness 0.15)
				)
				(justify mirror)
			)
		)
		(property "License" "Apache-2.0"
			(at 336.865 -59.335 0)
			(layer "B.Fab")
			(hide yes)
			(effects
				(font
					(size 1 1)
					(thickness 0.15)
				)
				(justify mirror)
			)
		)
		(property "MPN" "GRM155R61H104KE14D"
			(at 336.865 -59.335 0)
			(layer "B.Fab")
			(hide yes)
			(effects
				(font
					(size 1 1)
					(thickness 0.15)
				)
				(justify mirror)
			)
		)
		(property "Manufacturer" "Murata"
			(at 336.865 -59.335 0)
			(layer "B.Fab")
			(hide yes)
			(effects
				(font
					(size 1 1)
					(thickness 0.15)
				)
				(justify mirror)
			)
		)
		(property "Val" "100n"
			(at 336.865 -59.335 0)
			(layer "B.Fab")
			(hide yes)
			(effects
				(font
					(size 1 1)
					(thickness 0.15)
				)
				(justify mirror)
			)
		)
		(property "Voltage" "50V"
			(at 336.865 -59.335 0)
			(layer "B.Fab")
			(hide yes)
			(effects
				(font
					(size 1 1)
					(thickness 0.15)
				)
				(justify mirror)
			)
		)
		(sheetname "/Supply/")
		(sheetfile "supply.kicad_sch")
		(attr smd)
		(fp_rect
			(start -0.9659 0.481258)
			(end 0.9649 -0.458742)
			(stroke
				(width 0.05)
				(type solid)
			)
			(fill no)
			(layer "B.CrtYd")
		)
		(fp_line
			(start 0.499 -0.248)
			(end -0.499 -0.248)
			(stroke
				(width 0.15)
				(type solid)
			)
			(layer "B.Fab")
		)
		(fp_line
			(start -0.499 -0.248)
			(end -0.499 0.25)
			(stroke
				(width 0.15)
				(type solid)
			)
			(layer "B.Fab")
		)
		(fp_line
			(start 0.499 0.25)
			(end 0.499 -0.248)
			(stroke
				(width 0.15)
				(type solid)
			)
			(layer "B.Fab")
		)
		(fp_line
			(start -0.499 0.25)
			(end 0.499 0.25)
			(stroke
				(width 0.15)
				(type solid)
			)
			(layer "B.Fab")
		)
		(pad "1" smd roundrect
			(at -0.484 0 90)
			(size 0.59 0.64)
			(layers "B.Cu" "B.Mask" "B.Paste")
			(roundrect_rratio 0.25)
			(net 1 "GND")
			(pintype "passive")
		)
		(pad "2" smd roundrect
			(at 0.484 0 90)
			(size 0.59 0.64)
			(layers "B.Cu" "B.Mask" "B.Paste")
			(roundrect_rratio 0.25)
			(net 41 "+3V3_AON")
			(pintype "passive")
		)
	)
	(footprint "antmicro-footprints:R_0402_1005Metric"
		(layer "B.Cu")
		(at 140.302001 160.1 90)
		(descr "Resistor SMD 0402")
		(tags "resistor SMD 0402")
		(property "Reference" "R132"
			(at -1.122484 0.772697 270)
			(layer "B.SilkS")
			(hide yes)
			(effects
				(font
					(size 0.7 0.7)
					(thickness 0.15)
				)
				(justify left bottom mirror)
			)
		)
		(property "Value" "R_0R_0402"
			(at -1.011843 -1.772047 270)
			(layer "B.Fab")
			(effects
				(font
					(size 0.7 0.7)
					(thickness 0.15)
				)
				(justify left bottom mirror)
			)
		)
		(property "Datasheet" "https://industrial.panasonic.com/cdbs/www-data/pdf/RDA0000/AOA0000C301.pdf"
			(at 0 0 90)
			(layer "F.Fab")
			(hide yes)
			(effects
				(font
					(size 1.27 1.27)
					(thickness 0.15)
				)
			)
		)
		(property "Author" "Antmicro"
			(at 300.402001 19.797999 0)
			(layer "B.Fab")
			(hide yes)
			(effects
				(font
					(size 1 1)
					(thickness 0.15)
				)
				(justify mirror)
			)
		)
		(property "Current" "1A"
			(at 300.402001 19.797999 0)
			(layer "B.Fab")
			(hide yes)
			(effects
				(font
					(size 1 1)
					(thickness 0.15)
				)
				(justify mirror)
			)
		)
		(property "License" "Apache-2.0"
			(at 300.402001 19.797999 0)
			(layer "B.Fab")
			(hide yes)
			(effects
				(font
					(size 1 1)
					(thickness 0.15)
				)
				(justify mirror)
			)
		)
		(property "MPN" "ERJ2GE0R00X"
			(at 300.402001 19.797999 0)
			(layer "B.Fab")
			(hide yes)
			(effects
				(font
					(size 1 1)
					(thickness 0.15)
				)
				(justify mirror)
			)
		)
		(property "Manufacturer" "Panasonic"
			(at 300.402001 19.797999 0)
			(layer "B.Fab")
			(hide yes)
			(effects
				(font
					(size 1 1)
					(thickness 0.15)
				)
				(justify mirror)
			)
		)
		(property "Tolerance" ""
			(at 300.402001 19.797999 0)
			(layer "B.Fab")
			(hide yes)
			(effects
				(font
					(size 1 1)
					(thickness 0.15)
				)
				(justify mirror)
			)
		)
		(property "Val" "0R"
			(at 300.402001 19.797999 0)
			(layer "B.Fab")
			(hide yes)
			(effects
				(font
					(size 1 1)
					(thickness 0.15)
				)
				(justify mirror)
			)
		)
		(sheetname "/FPGA banks HP/")
		(sheetfile "fpga-banks-32-34.kicad_sch")
		(attr smd exclude_from_pos_files exclude_from_bom dnp)
		(fp_rect
			(start -0.93 0.47)
			(end 0.93 -0.47)
			(stroke
				(width 0.05)
				(type solid)
			)
			(fill no)
			(layer "B.CrtYd")
		)
		(fp_rect
			(start -0.5 0.25)
			(end 0.5 -0.25)
			(stroke
				(width 0.15)
				(type solid)
			)
			(fill no)
			(layer "B.Fab")
		)
		(pad "1" smd roundrect
			(at -0.485 0 90)
			(size 0.59 0.64)
			(layers "B.Cu" "B.Mask" "B.Paste")
			(roundrect_rratio 0.25)
			(net 379 "Net-(R129-Pad1)")
			(pintype "passive")
		)
		(pad "2" smd roundrect
			(at 0.485 0 90)
			(size 0.59 0.64)
			(layers "B.Cu" "B.Mask" "B.Paste")
			(roundrect_rratio 0.25)
			(net 10 "/FPGA banks HP/VREF")
			(pintype "passive")
		)
	)
)
